(kicad_pcb
	(version 20241229)
	(generator "pcbnew")
	(generator_version "9.0")
	(general
		(thickness 1.62)
		(legacy_teardrops no)
	)
	(paper "A3")
	(title_block
		(title "COM Express 7 Baseboard")
		(date "2025-02-04")
		(rev "1.1.2")
		(company "Antmicro Ltd")
		(comment 1 "www.antmicro.com")
		(comment 9 "footprints 547-550 of 802")
	)
	(layers
		(0 "F.Cu" signal)
		(4 "In1.Cu" signal)
		(6 "In2.Cu" signal)
		(8 "In3.Cu" signal)
		(10 "In4.Cu" signal)
		(12 "In5.Cu" signal)
		(14 "In6.Cu" signal)
		(2 "B.Cu" signal)
		(9 "F.Adhes" user "F.Adhesive")
		(11 "B.Adhes" user "B.Adhesive")
		(13 "F.Paste" user)
		(15 "B.Paste" user)
		(5 "F.SilkS" user "F.Silkscreen")
		(7 "B.SilkS" user "B.Silkscreen")
		(1 "F.Mask" user)
		(3 "B.Mask" user)
		(17 "Dwgs.User" user "User.Drawings")
		(19 "Cmts.User" user "User.Comments")
		(21 "Eco1.User" user "User.Eco1")
		(23 "Eco2.User" user "User.Eco2")
		(25 "Edge.Cuts" user)
		(27 "Margin" user)
		(31 "F.CrtYd" user "F.Courtyard")
		(29 "B.CrtYd" user "B.Courtyard")
		(35 "F.Fab" user)
		(33 "B.Fab" user)
	)
	(footprint "antmicro-footprints:C_0402_1005Metric"
		(layer "B.Cu")
		(at 136.29 137.36 -90)
		(descr "Capacitor SMD 0402")
		(tags "capacitor SMD 0402")
		(property "Reference" "C191"
			(at -1.4 0.49 90)
			(layer "B.SilkS")
			(effects
				(font
					(size 0.7 0.7)
					(thickness 0.15)
				)
				(justify left bottom mirror)
			)
		)
		(property "Value" "C_100n_0402"
			(at -1.022927 -2.155213 90)
			(layer "B.Fab")
			(effects
				(font
					(size 0.7 0.7)
					(thickness 0.15)
				)
				(justify left bottom mirror)
			)
		)
		(property "Datasheet" "https://www.murata.com/products/productdetail?partno=GRM155R61H104KE14%23"
			(at 0 0 270)
			(layer "F.Fab")
			(hide yes)
			(effects
				(font
					(size 1.27 1.27)
					(thickness 0.15)
				)
			)
		)
		(property "Author" "Antmicro"
			(at -1.07 273.65 0)
			(layer "B.Fab")
			(hide yes)
			(effects
				(font
					(size 1 1)
					(thickness 0.15)
				)
				(justify mirror)
			)
		)
		(property "Dielectric" "X5R"
			(at -1.07 273.65 0)
			(layer "B.Fab")
			(hide yes)
			(effects
				(font
					(size 1 1)
					(thickness 0.15)
				)
				(justify mirror)
			)
		)
		(property "License" "Apache-2.0"
			(at -1.07 273.65 0)
			(layer "B.Fab")
			(hide yes)
			(effects
				(font
					(size 1 1)
					(thickness 0.15)
				)
				(justify mirror)
			)
		)
		(property "MPN" "GRM155R61H104KE14D"
			(at -1.07 273.65 0)
			(layer "B.Fab")
			(hide yes)
			(effects
				(font
					(size 1 1)
					(thickness 0.15)
				)
				(justify mirror)
			)
		)
		(property "Manufacturer" "Murata"
			(at -1.07 273.65 0)
			(layer "B.Fab")
			(hide yes)
			(effects
				(font
					(size 1 1)
					(thickness 0.15)
				)
				(justify mirror)
			)
		)
		(property "Public" "False"
			(at -1.07 273.65 0)
			(layer "B.Fab")
			(hide yes)
			(effects
				(font
					(size 1 1)
					(thickness 0.15)
				)
				(justify mirror)
			)
		)
		(property "Val" "100n"
			(at -1.07 273.65 0)
			(layer "B.Fab")
			(hide yes)
			(effects
				(font
					(size 1 1)
					(thickness 0.15)
				)
				(justify mirror)
			)
		)
		(property "Voltage" "50V"
			(at -1.07 273.65 0)
			(layer "B.Fab")
			(hide yes)
			(effects
				(font
					(size 1 1)
					(thickness 0.15)
				)
				(justify mirror)
			)
		)
		(sheetname "KR to SFI #2")
		(sheetfile "kr_sfi.kicad_sch")
		(attr smd)
		(fp_rect
			(start -0.925 0.47)
			(end 0.925 -0.47)
			(stroke
				(width 0.05)
				(type default)
			)
			(fill no)
			(layer "B.CrtYd")
		)
		(fp_line
			(start -0.494 0.25)
			(end -0.494 -0.248)
			(stroke
				(width 0.15)
				(type solid)
			)
			(layer "B.Fab")
		)
		(fp_line
			(start 0.504 0.25)
			(end -0.494 0.25)
			(stroke
				(width 0.15)
				(type solid)
			)
			(layer "B.Fab")
		)
		(fp_line
			(start -0.494 -0.248)
			(end 0.504 -0.248)
			(stroke
				(width 0.15)
				(type solid)
			)
			(layer "B.Fab")
		)
		(fp_line
			(start 0.504 -0.248)
			(end 0.504 0.25)
			(stroke
				(width 0.15)
				(type solid)
			)
			(layer "B.Fab")
		)
		(pad "1" smd roundrect
			(at -0.48 0 270)
			(size 0.59 0.64)
			(layers "B.Cu" "B.Mask" "B.Paste")
			(roundrect_rratio 0.25)
			(net 1 "GND")
			(pintype "passive")
			(teardrops
				(best_length_ratio 0.2)
				(max_length 1)
				(best_width_ratio 0.9)
				(max_width 2)
				(curved_edges yes)
				(filter_ratio 0.9)
				(enabled yes)
				(allow_two_segments yes)
				(prefer_zone_connections yes)
			)
		)
		(pad "2" smd roundrect
			(at 0.48 0 270)
			(size 0.59 0.64)
			(layers "B.Cu" "B.Mask" "B.Paste")
			(roundrect_rratio 0.25)
			(net 74 "+1V0")
			(pintype "passive")
			(teardrops
				(best_length_ratio 0.2)
				(max_length 1)
				(best_width_ratio 0.9)
				(max_width 2)
				(curved_edges yes)
				(filter_ratio 0.9)
				(enabled yes)
				(allow_two_segments yes)
				(prefer_zone_connections yes)
			)
		)
	)
	(footprint "antmicro-footprints:R_0402_1005Metric"
		(layer "B.Cu")
		(at 104.44 155.66)
		(descr "Resistor SMD 0402")
		(tags "resistor SMD 0402")
		(property "Reference" "R81"
			(at 0.89 0.44 0)
			(layer "B.SilkS")
			(effects
				(font
					(size 0.7 0.7)
					(thickness 0.15)
				)
				(justify right bottom mirror)
			)
		)
		(property "Value" "R_0R_0402"
			(at -1.011843 -1.772047 0)
			(layer "B.Fab")
			(effects
				(font
					(size 0.7 0.7)
					(thickness 0.15)
				)
				(justify right bottom mirror)
			)
		)
		(property "Datasheet" "https://industrial.panasonic.com/cdbs/www-data/pdf/RDA0000/AOA0000C301.pdf"
			(at 0 0 0)
			(layer "F.Fab")
			(hide yes)
			(effects
				(font
					(size 1.27 1.27)
					(thickness 0.15)
				)
			)
		)
		(property "Author" "Antmicro"
			(at 0 0 0)
			(layer "B.Fab")
			(hide yes)
			(effects
				(font
					(size 1 1)
					(thickness 0.15)
				)
				(justify mirror)
			)
		)
		(property "Current" "1A"
			(at 0 0 0)
			(layer "B.Fab")
			(hide yes)
			(effects
				(font
					(size 1 1)
					(thickness 0.15)
				)
				(justify mirror)
			)
		)
		(property "License" "Apache-2.0"
			(at 0 0 0)
			(layer "B.Fab")
			(hide yes)
			(effects
				(font
					(size 1 1)
					(thickness 0.15)
				)
				(justify mirror)
			)
		)
		(property "MPN" "ERJ2GE0R00X"
			(at 0 0 0)
			(layer "B.Fab")
			(hide yes)
			(effects
				(font
					(size 1 1)
					(thickness 0.15)
				)
				(justify mirror)
			)
		)
		(property "Manufacturer" "Panasonic"
			(at 0 0 0)
			(layer "B.Fab")
			(hide yes)
			(effects
				(font
					(size 1 1)
					(thickness 0.15)
				)
				(justify mirror)
			)
		)
		(property "Public" "False"
			(at 0 0 0)
			(layer "B.Fab")
			(hide yes)
			(effects
				(font
					(size 1 1)
					(thickness 0.15)
				)
				(justify mirror)
			)
		)
		(property "Tolerance" ""
			(at 0 0 0)
			(layer "B.Fab")
			(hide yes)
			(effects
				(font
					(size 1 1)
					(thickness 0.15)
				)
				(justify mirror)
			)
		)
		(property "Val" "0R"
			(at 0 0 0)
			(layer "B.Fab")
			(hide yes)
			(effects
				(font
					(size 1 1)
					(thickness 0.15)
				)
				(justify mirror)
			)
		)
		(sheetname "OCuLink")
		(sheetfile "oculink.kicad_sch")
		(attr smd)
		(fp_rect
			(start -0.925 0.47)
			(end 0.925 -0.47)
			(stroke
				(width 0.05)
				(type default)
			)
			(fill no)
			(layer "B.CrtYd")
		)
		(fp_rect
			(start -0.5 0.25)
			(end 0.5 -0.25)
			(stroke
				(width 0.15)
				(type solid)
			)
			(fill no)
			(layer "B.Fab")
		)
		(pad "1" smd roundrect
			(at -0.48 0)
			(size 0.59 0.64)
			(layers "B.Cu" "B.Mask" "B.Paste")
			(roundrect_rratio 0.25)
			(net 59 "/OCuLink/V_{ACT_TX}0")
			(pintype "passive")
			(teardrops
				(best_length_ratio 0.2)
				(max_length 1)
				(best_width_ratio 0.9)
				(max_width 2)
				(curved_edges yes)
				(filter_ratio 0.9)
				(enabled yes)
				(allow_two_segments yes)
				(prefer_zone_connections yes)
			)
		)
		(pad "2" smd roundrect
			(at 0.48 0)
			(size 0.59 0.64)
			(layers "B.Cu" "B.Mask" "B.Paste")
			(roundrect_rratio 0.25)
			(net 2 "+3V3")
			(pintype "passive")
			(teardrops
				(best_length_ratio 0.2)
				(max_length 1)
				(best_width_ratio 0.9)
				(max_width 2)
				(curved_edges yes)
				(filter_ratio 0.9)
				(enabled yes)
				(allow_two_segments yes)
				(prefer_zone_connections yes)
			)
		)
	)
	(footprint "antmicro-footprints:USON-10_2.5x1mm_P0.5mm"
		(layer "B.Cu")
		(at 104.767002 162.61)
		(descr "USON-10 2.5x1mm_ Pitch 0.5mm")
		(tags "USON-10 2.5x1mm Pitch 0.5mm")
		(property "Reference" "U35"
			(at 1.712998 1.07 90)
			(layer "B.SilkS")
			(effects
				(font
					(size 0.7 0.7)
					(thickness 0.15)
				)
				(justify right bottom mirror)
			)
		)
		(property "Value" "ESD204DQAR"
			(at 0.018 -2.499 0)
			(layer "B.Fab")
			(effects
				(font
					(size 0.7 0.7)
					(thickness 0.15)
				)
				(justify right bottom mirror)
			)
		)
		(property "Datasheet" "https://www.ti.com/lit/ds/symlink/esd204.pdf?ts=1706004844383&ref_url=https%253A%252F%252Fwww.ti.com%252Finterface%252Fdiodes%252Fesd-protection-diodes%252Fproducts.html"
			(at 0 0 0)
			(layer "F.Fab")
			(hide yes)
			(effects
				(font
					(size 1.27 1.27)
					(thickness 0.15)
				)
			)
		)
		(property "Author" "Antmicro"
			(at 0 0 0)
			(layer "B.Fab")
			(hide yes)
			(effects
				(font
					(size 1 1)
					(thickness 0.15)
				)
				(justify mirror)
			)
		)
		(property "License" "Apache-2.0"
			(at 0 0 0)
			(layer "B.Fab")
			(hide yes)
			(effects
				(font
					(size 1 1)
					(thickness 0.15)
				)
				(justify mirror)
			)
		)
		(property "MPN" "ESD204DQAR"
			(at 0 0 0)
			(layer "B.Fab")
			(hide yes)
			(effects
				(font
					(size 1 1)
					(thickness 0.15)
				)
				(justify mirror)
			)
		)
		(property "Manufacturer" "Texas Instruments"
			(at 0 0 0)
			(layer "B.Fab")
			(hide yes)
			(effects
				(font
					(size 1 1)
					(thickness 0.15)
				)
				(justify mirror)
			)
		)
		(sheetname "OCuLink")
		(sheetfile "oculink.kicad_sch")
		(attr smd)
		(fp_line
			(start -0.5 -1.398)
			(end 0.498 -1.398)
			(stroke
				(width 0.15)
				(type solid)
			)
			(layer "B.SilkS")
		)
		(fp_line
			(start -0.5 1.401)
			(end 0.498 1.401)
			(stroke
				(width 0.15)
				(type solid)
			)
			(layer "B.SilkS")
		)
		(fp_circle
			(center -0.68 1.27)
			(end -0.63 1.27)
			(stroke
				(width 0.15)
				(type solid)
			)
			(fill yes)
			(layer "B.SilkS")
		)
		(fp_rect
			(start -0.8 1.5)
			(end 0.8 -1.499)
			(stroke
				(width 0.05)
				(type solid)
			)
			(fill no)
			(layer "B.CrtYd")
		)
		(fp_line
			(start -0.5 -1.249)
			(end -0.5 1)
			(stroke
				(width 0.15)
				(type solid)
			)
			(layer "B.Fab")
		)
		(fp_line
			(start -0.5 1)
			(end -0.25 1.25)
			(stroke
				(width 0.15)
				(type solid)
			)
			(layer "B.Fab")
		)
		(fp_line
			(start -0.25 1.25)
			(end 0.498 1.25)
			(stroke
				(width 0.15)
				(type solid)
			)
			(layer "B.Fab")
		)
		(fp_line
			(start 0.498 -1.249)
			(end -0.5 -1.249)
			(stroke
				(width 0.15)
				(type solid)
			)
			(layer "B.Fab")
		)
		(fp_line
			(start 0.498 -1.249)
			(end 0.498 1.25)
			(stroke
				(width 0.15)
				(type solid)
			)
			(layer "B.Fab")
		)
		(pad "1" smd roundrect
			(at -0.387 1 90)
			(size 0.25 0.55)
			(layers "B.Cu" "B.Mask" "B.Paste")
			(roundrect_rratio 0.25)
			(net 198 "/OCuLink/SCL")
			(pintype "passive")
			(teardrops
				(best_length_ratio 0.2)
				(max_length 1)
				(best_width_ratio 0.9)
				(max_width 2)
				(curved_edges yes)
				(filter_ratio 0.9)
				(enabled yes)
				(allow_two_segments yes)
				(prefer_zone_connections yes)
			)
		)
		(pad "2" smd roundrect
			(at -0.387 0.5 90)
			(size 0.25 0.55)
			(layers "B.Cu" "B.Mask" "B.Paste")
			(roundrect_rratio 0.25)
			(net 199 "/OCuLink/SDA")
			(pintype "passive")
			(teardrops
				(best_length_ratio 0.2)
				(max_length 1)
				(best_width_ratio 0.9)
				(max_width 2)
				(curved_edges yes)
				(filter_ratio 0.9)
				(enabled yes)
				(allow_two_segments yes)
				(prefer_zone_connections yes)
			)
		)
		(pad "3" smd roundrect
			(at -0.387 0 90)
			(size 0.4 0.55)
			(layers "B.Cu" "B.Mask" "B.Paste")
			(roundrect_rratio 0.25)
			(net 1 "GND")
			(pintype "power_in")
			(teardrops
				(best_length_ratio 0.2)
				(max_length 1)
				(best_width_ratio 0.9)
				(max_width 2)
				(curved_edges yes)
				(filter_ratio 0.9)
				(enabled yes)
				(allow_two_segments yes)
				(prefer_zone_connections yes)
			)
		)
		(pad "4" smd roundrect
			(at -0.387 -0.498 90)
			(size 0.25 0.55)
			(layers "B.Cu" "B.Mask" "B.Paste")
			(roundrect_rratio 0.25)
			(net 200 "/OCuLink/~{PERST_D0}")
			(pintype "passive")
			(teardrops
				(best_length_ratio 0.2)
				(max_length 1)
				(best_width_ratio 0.9)
				(max_width 2)
				(curved_edges yes)
				(filter_ratio 0.9)
				(enabled yes)
				(allow_two_segments yes)
				(prefer_zone_connections yes)
			)
		)
		(pad "5" smd roundrect
			(at -0.387 -0.998 90)
			(size 0.25 0.55)
			(layers "B.Cu" "B.Mask" "B.Paste")
			(roundrect_rratio 0.25)
			(net 201 "/OCuLink/~{CPRSNT_D0}")
			(pintype "passive")
			(teardrops
				(best_length_ratio 0.2)
				(max_length 1)
				(best_width_ratio 0.9)
				(max_width 2)
				(curved_edges yes)
				(filter_ratio 0.9)
				(enabled yes)
				(allow_two_segments yes)
				(prefer_zone_connections yes)
			)
		)
		(pad "6" smd roundrect
			(at 0.385 -0.998 90)
			(size 0.25 0.55)
			(layers "B.Cu" "B.Mask" "B.Paste")
			(roundrect_rratio 0.25)
			(net 201 "/OCuLink/~{CPRSNT_D0}")
			(pintype "passive")
			(teardrops
				(best_length_ratio 0.2)
				(max_length 1)
				(best_width_ratio 0.9)
				(max_width 2)
				(curved_edges yes)
				(filter_ratio 0.9)
				(enabled yes)
				(allow_two_segments yes)
				(prefer_zone_connections yes)
			)
		)
		(pad "7" smd roundrect
			(at 0.385 -0.498 90)
			(size 0.25 0.55)
			(layers "B.Cu" "B.Mask" "B.Paste")
			(roundrect_rratio 0.25)
			(net 200 "/OCuLink/~{PERST_D0}")
			(pintype "passive")
			(teardrops
				(best_length_ratio 0.2)
				(max_length 1)
				(best_width_ratio 0.9)
				(max_width 2)
				(curved_edges yes)
				(filter_ratio 0.9)
				(enabled yes)
				(allow_two_segments yes)
				(prefer_zone_connections yes)
			)
		)
		(pad "8" smd roundrect
			(at 0.385 0 90)
			(size 0.4 0.55)
			(layers "B.Cu" "B.Mask" "B.Paste")
			(roundrect_rratio 0.25)
			(net 1 "GND")
			(pintype "passive")
			(teardrops
				(best_length_ratio 0.2)
				(max_length 1)
				(best_width_ratio 0.9)
				(max_width 2)
				(curved_edges yes)
				(filter_ratio 0.9)
				(enabled yes)
				(allow_two_segments yes)
				(prefer_zone_connections yes)
			)
		)
		(pad "9" smd roundrect
			(at 0.385 0.5 90)
			(size 0.25 0.55)
			(layers "B.Cu" "B.Mask" "B.Paste")
			(roundrect_rratio 0.25)
			(net 199 "/OCuLink/SDA")
			(pintype "passive")
			(teardrops
				(best_length_ratio 0.2)
				(max_length 1)
				(best_width_ratio 0.9)
				(max_width 2)
				(curved_edges yes)
				(filter_ratio 0.9)
				(enabled yes)
				(allow_two_segments yes)
				(prefer_zone_connections yes)
			)
		)
		(pad "10" smd roundrect
			(at 0.385 1 90)
			(size 0.25 0.55)
			(layers "B.Cu" "B.Mask" "B.Paste")
			(roundrect_rratio 0.25)
			(net 198 "/OCuLink/SCL")
			(pintype "passive")
			(teardrops
				(best_length_ratio 0.2)
				(max_length 1)
				(best_width_ratio 0.9)
				(max_width 2)
				(curved_edges yes)
				(filter_ratio 0.9)
				(enabled yes)
				(allow_two_segments yes)
				(prefer_zone_connections yes)
			)
		)
	)
	(footprint "antmicro-footprints:R_0402_1005Metric"
		(layer "B.Cu")
		(at 126.09 137.06 180)
		(descr "Resistor SMD 0402")
		(tags "resistor SMD 0402")
		(property "Reference" "R296"
			(at 0.79 -0.4 0)
			(layer "B.SilkS")
			(effects
				(font
					(size 0.7 0.7)
					(thickness 0.15)
				)
				(justify left bottom mirror)
			)
		)
		(property "Value" "R_10k_0402"
			(at -1.011843 -1.772047 0)
			(layer "B.Fab")
			(effects
				(font
					(size 0.7 0.7)
					(thickness 0.15)
				)
				(justify left bottom mirror)
			)
		)
		(property "Datasheet" "https://www.bourns.com/docs/product-datasheets/cr.pdf"
			(at 0 0 180)
			(layer "F.Fab")
			(hide yes)
			(effects
				(font
					(size 1.27 1.27)
					(thickness 0.15)
				)
			)
		)
		(property "Author" "Antmicro"
			(at 252.18 274.12 0)
			(layer "B.Fab")
			(hide yes)
			(effects
				(font
					(size 1 1)
					(thickness 0.15)
				)
				(justify mirror)
			)
		)
		(property "License" "Apache-2.0"
			(at 252.18 274.12 0)
			(layer "B.Fab")
			(hide yes)
			(effects
				(font
					(size 1 1)
					(thickness 0.15)
				)
				(justify mirror)
			)
		)
		(property "MPN" "CR0402-FX-1002GLF"
			(at 252.18 274.12 0)
			(layer "B.Fab")
			(hide yes)
			(effects
				(font
					(size 1 1)
					(thickness 0.15)
				)
				(justify mirror)
			)
		)
		(property "Manufacturer" "Bourns"
			(at 252.18 274.12 0)
			(layer "B.Fab")
			(hide yes)
			(effects
				(font
					(size 1 1)
					(thickness 0.15)
				)
				(justify mirror)
			)
		)
		(property "Public" "False"
			(at 252.18 274.12 0)
			(layer "B.Fab")
			(hide yes)
			(effects
				(font
					(size 1 1)
					(thickness 0.15)
				)
				(justify mirror)
			)
		)
		(property "Tolerance" "1%"
			(at 252.18 274.12 0)
			(layer "B.Fab")
			(hide yes)
			(effects
				(font
					(size 1 1)
					(thickness 0.15)
				)
				(justify mirror)
			)
		)
		(property "Val" "10k"
			(at 252.18 274.12 0)
			(layer "B.Fab")
			(hide yes)
			(effects
				(font
					(size 1 1)
					(thickness 0.15)
				)
				(justify mirror)
			)
		)
		(sheetname "KR to SFI #2")
		(sheetfile "kr_sfi.kicad_sch")
		(attr smd dnp)
		(fp_rect
			(start -0.925 0.47)
			(end 0.925 -0.47)
			(stroke
				(width 0.05)
				(type default)
			)
			(fill no)
			(layer "B.CrtYd")
		)
		(fp_rect
			(start -0.5 0.25)
			(end 0.5 -0.25)
			(stroke
				(width 0.15)
				(type solid)
			)
			(fill no)
			(layer "B.Fab")
		)
		(pad "1" smd roundrect
			(at -0.48 0 180)
			(size 0.59 0.64)
			(layers "B.Cu" "B.Mask" "B.Paste")
			(roundrect_rratio 0.25)
			(net 677 "Net-(U45C-PRTAD1)")
			(pintype "passive")
			(teardrops
				(best_length_ratio 0.2)
				(max_length 1)
				(best_width_ratio 0.9)
				(max_width 2)
				(curved_edges yes)
				(filter_ratio 0.9)
				(enabled yes)
				(allow_two_segments yes)
				(prefer_zone_connections yes)
			)
		)
		(pad "2" smd roundrect
			(at 0.48 0 180)
			(size 0.59 0.64)
			(layers "B.Cu" "B.Mask" "B.Paste")
			(roundrect_rratio 0.25)
			(net 78 "+1V8")
			(pintype "passive")
			(teardrops
				(best_length_ratio 0.2)
				(max_length 1)
				(best_width_ratio 0.9)
				(max_width 2)
				(curved_edges yes)
				(filter_ratio 0.9)
				(enabled yes)
				(allow_two_segments yes)
				(prefer_zone_connections yes)
			)
		)
	)
)
